# T6G (Grand Teton) — schematic parts with pin connectivity, parts 2613–2613 of 8303; source: Cadence DE-HDL packaged netlist (pstxprt.dat, pstxnet.dat, pstchip.dat)

J35  SCONN168_ME1016810202011  IO  pkg CON_F168S2H7D_P0-6W2-95_LUH  page 137
  A1  GND_A1  POWER  = GND
  A2  GND_A2  POWER  = GND
  A3  GND_A3  POWER  = GND
  A4  GND_A4  POWER  = GND
  A5  GND_A5  POWER  = GND
  A6  GND_A6  POWER  = GND
  A7  SMCLK  OUT  = SMB_OCP_V3_2_3V3AUX_BUF_R_SCL
  A8  SMDAT  BI  = SMB_OCP_V3_2_3V3AUX_BUF_R_SDA
  A9  \smrst#\  OUT  = RST_SMB_OCP_V3_2_N
  A10  \prsnta#\  OUT  = OCP_V3_2_PRSNTA_R_N
  A11  \perst1#\  OUT  = RST_PERST1_OCP_V3_2_N
  A12  \prsntb2#\  IN  = OCP_V3_2_PRSNT2_R_N
  A13  GND_A13  POWER  = GND
  A14  REFCLKN1  OUT  = CLK_100M_CPU1_CLK03_DN
  A15  REFCLKP1  OUT  = CLK_100M_CPU1_CLK03_DP
  A16  GND_A16  POWER  = GND
  A17  PERN0  IN  = P5E_CPU1_G1_RX_DN<0>
  A18  PERP0  IN  = P5E_CPU1_G1_RX_DP<0>
  A19  GND_A19  POWER  = GND
  A20  PERN1  IN  = P5E_CPU1_G1_RX_DN<1>
  A21  PERP1  IN  = P5E_CPU1_G1_RX_DP<1>
  A22  GND_A22  POWER  = GND
  A23  PERN2  IN  = P5E_CPU1_G1_RX_DN<2>
  A24  PERP2  IN  = P5E_CPU1_G1_RX_DP<2>
  A25  GND_A25  POWER  = GND
  A26  PERN3  IN  = P5E_CPU1_G1_RX_DN<3>
  A27  PERP3  IN  = P5E_CPU1_G1_RX_DP<3>
  A28  GND_A28  POWER  = GND
  A29  GND_A29  POWER  = GND
  A30  PERN4  IN  = P5E_CPU1_G1_RX_DN<4>
  A31  PERP4  IN  = P5E_CPU1_G1_RX_DP<4>
  A32  GND_A32  POWER  = GND
  A33  PERN5  IN  = P5E_CPU1_G1_RX_DN<5>
  A34  PERP5  IN  = P5E_CPU1_G1_RX_DP<5>
  A35  GND_A35  POWER  = GND
  A36  PERN6  IN  = P5E_CPU1_G1_RX_DN<6>
  A37  PERP6  IN  = P5E_CPU1_G1_RX_DP<6>
  A38  GND_A38  POWER  = GND
  A39  PERN7  IN  = P5E_CPU1_G1_RX_DN<7>
  A40  PERP7  IN  = P5E_CPU1_G1_RX_DP<7>
  A41  GND_A41  POWER  = GND
  A42  \prsntb1#\  IN  = OCP_V3_2_PRSNT1_R_N
  A43  GND_A43  POWER  = GND
  A44  PERN8  IN  = P5E_CPU1_G1_RX_DN<8>
  A45  PERP8  IN  = P5E_CPU1_G1_RX_DP<8>
  A46  GND_A46  POWER  = GND
  A47  PERN9  IN  = P5E_CPU1_G1_RX_DN<9>
  A48  PERP9  IN  = P5E_CPU1_G1_RX_DP<9>
  A49  GND_A49  POWER  = GND
  A50  PERN10  IN  = P5E_CPU1_G1_RX_DN<10>
  A51  PERP10  IN  = P5E_CPU1_G1_RX_DP<10>
  A52  GND_A52  POWER  = GND
  A53  PERN11  IN  = P5E_CPU1_G1_RX_DN<11>
  A54  PERP11  IN  = P5E_CPU1_G1_RX_DP<11>
  A55  GND_A55  POWER  = GND
  A56  PERN12  IN  = P5E_CPU1_G1_RX_DN<12>
  A57  PERP12  IN  = P5E_CPU1_G1_RX_DP<12>
  A58  GND_A58  POWER  = GND
  A59  PERN13  IN  = P5E_CPU1_G1_RX_DN<13>
  A60  PERP13  IN  = P5E_CPU1_G1_RX_DP<13>
  A61  GND_A61  POWER  = GND
  A62  PERN14  IN  = P5E_CPU1_G1_RX_DN<14>
  A63  PERP14  IN  = P5E_CPU1_G1_RX_DP<14>
  A64  GND_A64  POWER  = GND
  A65  PERN15  IN  = P5E_CPU1_G1_RX_DN<15>
  A66  PERP15  IN  = P5E_CPU1_G1_RX_DP<15>
  A67  GND_A67  POWER  = GND
  A68  USB_DATN  BI  = USB2_P10_DN
  A69  USB_DATP  BI  = USB2_P10_DP
  A70  \pwrbrk0#\  BI  = OCP_V3_2_PWRBRK_N
  B1  \+12v_edge_b1\  POWER  = P12V_OCP_V3_2_R
  B2  \+12v_edge_b2\  POWER  = P12V_OCP_V3_2_R
  B3  \+12v_edge_b3\  POWER  = P12V_OCP_V3_2_R
  B4  \+12v_edge_b4\  POWER  = P12V_OCP_V3_2_R
  B5  \+12v_edge_b5\  POWER  = P12V_OCP_V3_2_R
  B6  \+12v_edge_b6\  POWER  = P12V_OCP_V3_2_R
  B7  \bif0#\  OUT  = OCP_V3_2_BIF0_R_N
  B8  \bif1#\  OUT  = OCP_V3_2_BIF1_R_N
  B9  \bif2#\  OUT  = OCP_V3_2_BIF2_R_N
  B10  \perst0#\  OUT  = RST_PERST0_OCP_V3_2_N
  B11  \+3.3v_edge\  POWER  = P3V3_OCP_V3_2
  B12  AUX_PWR_EN  OUT  = OCP_V3_2_AUX_PWR_EN_R
  B13  GND_B13  POWER  = GND
  B14  REFCLKN0  IN  = CLK_100M_CPU1_CLK02_DN
  B15  REFCLKP0  OUT  = CLK_100M_CPU1_CLK02_DP
  B16  GND_B16  POWER  = GND
  B17  PETN0  OUT  = P5E_CPU1_G1_TX_C_DP<0>
  B18  PETP0  OUT  = P5E_CPU1_G1_TX_C_DN<0>
  B19  GND_B19  POWER  = GND
  B20  PETN1  OUT  = P5E_CPU1_G1_TX_C_DP<1>
  B21  PETP1  OUT  = P5E_CPU1_G1_TX_C_DN<1>
  B22  GND_B22  POWER  = GND
  B23  PETN2  OUT  = P5E_CPU1_G1_TX_C_DP<2>
  B24  PETP2  OUT  = P5E_CPU1_G1_TX_C_DN<2>
  B25  GND_B25  POWER  = GND
  B26  PETN3  OUT  = P5E_CPU1_G1_TX_C_DP<3>
  B27  PETP3  OUT  = P5E_CPU1_G1_TX_C_DN<3>
  B28  GND_B28  POWER  = GND
  B29  GND_B29  POWER  = GND
  B30  PETN4  OUT  = P5E_CPU1_G1_TX_C_DP<4>
  B31  PETP4  OUT  = P5E_CPU1_G1_TX_C_DN<4>
  B32  GND_B32  POWER  = GND
  B33  PETN5  OUT  = P5E_CPU1_G1_TX_C_DP<5>
  B34  PETP5  OUT  = P5E_CPU1_G1_TX_C_DN<5>
  B35  GND_B35  POWER  = GND
  B36  PETN6  OUT  = P5E_CPU1_G1_TX_C_DP<6>
  B37  PETP6  OUT  = P5E_CPU1_G1_TX_C_DN<6>
  B38  GND_B38  POWER  = GND
  B39  PETN7  OUT  = P5E_CPU1_G1_TX_C_DP<7>
  B40  PETP7  OUT  = P5E_CPU1_G1_TX_C_DN<7>
  B41  GND_B41  POWER  = GND
  B42  \prsntb0#\  IN  = OCP_V3_2_PRSNT0_R_N
  B43  GND_B43  POWER  = GND
  B44  PETN8  OUT  = P5E_CPU1_G1_TX_C_DP<8>
  B45  PETP8  OUT  = P5E_CPU1_G1_TX_C_DN<8>
  B46  GND_B46  POWER  = GND
  B47  PETN9  OUT  = P5E_CPU1_G1_TX_C_DP<9>
  B48  PETP9  OUT  = P5E_CPU1_G1_TX_C_DN<9>
  B49  GND_B49  POWER  = GND
  B50  PETN10  OUT  = P5E_CPU1_G1_TX_C_DP<10>
  B51  PETP10  OUT  = P5E_CPU1_G1_TX_C_DN<10>
  B52  GND_B52  POWER  = GND
  B53  PETN11  OUT  = P5E_CPU1_G1_TX_C_DP<11>
  B54  PETP11  OUT  = P5E_CPU1_G1_TX_C_DN<11>
  B55  GND_B55  POWER  = GND
  B56  PETN12  OUT  = P5E_CPU1_G1_TX_C_DP<12>
  B57  PETP12  OUT  = P5E_CPU1_G1_TX_C_DN<12>
  B58  GND_B58  POWER  = GND
  B59  PETN13  OUT  = P5E_CPU1_G1_TX_C_DP<13>
  B60  PETP13  OUT  = P5E_CPU1_G1_TX_C_DN<13>
  B61  GND_B61  POWER  = GND
  B62  PETN14  OUT  = P5E_CPU1_G1_TX_C_DP<14>
  B63  PETP14  OUT  = P5E_CPU1_G1_TX_C_DN<14>
  B64  GND_B64  POWER  = GND
  B65  PETN15  OUT  = P5E_CPU1_G1_TX_C_DP<15>
  B66  PETP15  OUT  = P5E_CPU1_G1_TX_C_DN<15>
  B67  GND_B67  POWER  = GND
  B68  RFU1_NC_B68  TRI  = TP_OCP_V3_2_B68
  B69  RFU1_NC_B69  TRI  = TP_OCP_V3_2_B69
  B70  \prsntb3#\  IN  = OCP_V3_2_PRSNT3_R_N
  G1  G1  POWER  = GND
  G2  G2  POWER  = GND
  G3  G3  POWER  = GND
  G4  G4  POWER  = GND
  G5  G5  POWER  = GND
  OA1  \perst2#\  OUT  = RST_PERST2_OCP_V3_2_N
  OA2  \perst3#\  OUT  = RST_PERST3_OCP_V3_2_N
  OA3  \wake#\  IN  = IRQ_LVC3_OCP_V3_2_WAKE_N
  OA4  RBT_ARB_IN  IN  = OCP_V3_2_ISO1_RBT_ARB_IN
  OA5  RBT_ARB_OUT  OUT  = OCP_V3_2_ISO2_RBT_ARB_OUT
  OA6  SLOT_ID1  OUT  = OCP_V3_2_ID1
  OA7  RBT_TX_EN  OUT  = NCSI_OCP_V3_2_TX_EN
  OA8  RBT_TXD1  OUT  = NCSI_OCP_V3_2_TXD1
  OA9  RBT_TXD0  OUT  = NCSI_OCP_V3_2_TXD0
  OA10  GND_OA10  POWER  = GND
  OA11  REFCLKN3  OUT  = CLK_100M_CPU1_CLK05_DN
  OA12  REFCLKP3  OUT  = CLK_100M_CPU1_CLK05_DP
  OA13  GND_OA13  POWER  = GND
  OA14  RBT_CLK_IN  OUT  = CLK_50M_NCSI_OCP_V3_2_ISO
  OB1  NIC_PWR_GOOD  IN  = FM_OCP_V3_2_PWR_GOOD
  OB2  MAIN_PWR_EN  OUT  = OCP_V3_2_MAIN_PWR_EN_R
  OB3  \ld#\  OUT  = SGPIO_OCP_V3_2_LD_N
  OB4  DATA_IN  IN  = SGPIO_OCP_V3_2_DATAIN
  OB5  DATA_OUT  OUT  = SGPIO_OCP_V3_2_DATAOUT
  OB6  CLK  OUT  = SGPIO_OCP_V3_2_CLK
  OB7  SLOT_ID0  OUT  = OCP_V3_2_ID0
  OB8  RBT_RXD1  IN  = NCSI_OCP_V3_2_RXD1
  OB9  RBT_RXD0  IN  = NCSI_OCP_V3_2_RXD0
  OB10  GND_OB10  POWER  = GND
  OB11  REFCLKN2  OUT  = CLK_100M_CPU1_CLK04_DN
  OB12  REFCLKP2  OUT  = CLK_100M_CPU1_CLK04_DP
  OB13  GND_OB13  POWER  = GND
  OB14  RBT_CRS_DV  OUT  = NCSI_OCP_V3_2_CRS_DV
